(kicad_pcb
	(version 20260206)
	(generator "pcbnew")
	(generator_version "10.0")
	(general
		(thickness 1.6)
		(legacy_teardrops no)
	)
	(paper "A4")
	(title_block
		(title "03242023_DA0F0TMBIJ0_F0T_Motherboard_J_brd_V01_OCP.brd")
		(comment 1 "Grand Teton / footprints 3216-3220 of 6105")
	)
	(layers
		(0 "F.Cu" signal "TOP")
		(4 "In1.Cu" signal "GND")
		(6 "In2.Cu" signal "IN1")
		(8 "In3.Cu" signal "GND1")
		(10 "In4.Cu" signal "IN2")
		(12 "In5.Cu" signal "GND2")
		(14 "In6.Cu" signal "IN3")
		(16 "In7.Cu" signal "GND3")
		(18 "In8.Cu" signal "VCC")
		(20 "In9.Cu" signal "VCC1")
		(22 "In10.Cu" signal "GND4")
		(24 "In11.Cu" signal "IN4")
		(26 "In12.Cu" signal "GND5")
		(28 "In13.Cu" signal "IN5")
		(30 "In14.Cu" signal "GND6")
		(32 "In15.Cu" signal "IN6")
		(34 "In16.Cu" signal "GND7")
		(2 "B.Cu" signal "BOTTOM")
		(9 "F.Adhes" user "F.Adhesive")
		(11 "B.Adhes" user "B.Adhesive")
		(13 "F.Paste" user "Package Geometry/Pastemask Top")
		(15 "B.Paste" user "Package Geometry/Pastemask Bottom")
		(5 "F.SilkS" user "Ref Des/Silkscreen Top")
		(7 "B.SilkS" user "Ref Des/Silkscreen Bottom")
		(1 "F.Mask" user "Board Geometry/Soldermask Top")
		(3 "B.Mask" user "Board Geometry/Soldermask Bottom")
		(17 "Dwgs.User" user "User.Drawings")
		(19 "Cmts.User" user "User.Comments")
		(21 "Eco1.User" user "User.Eco1")
		(23 "Eco2.User" user "User.Eco2")
		(25 "Edge.Cuts" user "Board Geometry/Outline")
		(27 "Margin" user)
		(31 "F.CrtYd" user "Package Geometry/Place Bound Top")
		(29 "B.CrtYd" user "Package Geometry/Place Bound Bottom")
		(35 "F.Fab" user "Ref Des/Assembly Top")
		(33 "B.Fab" user "Ref Des/Assembly Bottom")
	)
	(footprint ""
		(layer "F.Cu")
		(at 423.513504 -131.975352 -90)
		(property "Reference" "PC224"
			(at 0 0 270)
			(layer "F.SilkS")
			(hide yes)
			(effects
				(font
					(size 1.27 1.27)
				)
			)
		)
		(property "Value" ""
			(at 0 0 270)
			(layer "F.Fab")
			(effects
				(font
					(size 1.27 1.27)
				)
			)
		)
		(duplicate_pad_numbers_are_jumpers no)
		(fp_line
			(start -0.7874 0.4064)
			(end -0.7874 -0.4064)
			(stroke
				(width 0.1524)
				(type default)
			)
			(layer "F.SilkS")
		)
		(fp_line
			(start 0.7874 0.4064)
			(end -0.7874 0.4064)
			(stroke
				(width 0.1524)
				(type default)
			)
			(layer "F.SilkS")
		)
		(fp_line
			(start -0.7874 -0.4064)
			(end 0.7874 -0.4064)
			(stroke
				(width 0.1524)
				(type default)
			)
			(layer "F.SilkS")
		)
		(fp_line
			(start 0.7874 -0.4064)
			(end 0.7874 0.4064)
			(stroke
				(width 0.1524)
				(type default)
			)
			(layer "F.SilkS")
		)
		(fp_line
			(start -0.67945 0.3048)
			(end -0.67945 -0.305054)
			(stroke
				(width 0.1)
				(type default)
			)
			(layer "F.Fab")
		)
		(fp_line
			(start -0.12065 0.3048)
			(end -0.67945 0.3048)
			(stroke
				(width 0.1)
				(type default)
			)
			(layer "F.Fab")
		)
		(fp_line
			(start 0.120396 0.3048)
			(end 0.120396 0.2794)
			(stroke
				(width 0.1)
				(type default)
			)
			(layer "F.Fab")
		)
		(fp_line
			(start 0.67945 0.3048)
			(end 0.120396 0.3048)
			(stroke
				(width 0.1)
				(type default)
			)
			(layer "F.Fab")
		)
		(fp_line
			(start -0.12065 0.2794)
			(end -0.12065 0.3048)
			(stroke
				(width 0.1)
				(type default)
			)
			(layer "F.Fab")
		)
		(fp_line
			(start 0.120396 0.2794)
			(end -0.12065 0.2794)
			(stroke
				(width 0.1)
				(type default)
			)
			(layer "F.Fab")
		)
		(fp_line
			(start -0.12065 -0.2794)
			(end 0.12065 -0.2794)
			(stroke
				(width 0.1)
				(type default)
			)
			(layer "F.Fab")
		)
		(fp_line
			(start 0.12065 -0.2794)
			(end 0.12065 -0.3048)
			(stroke
				(width 0.1)
				(type default)
			)
			(layer "F.Fab")
		)
		(fp_line
			(start 0.12065 -0.3048)
			(end 0.67945 -0.3048)
			(stroke
				(width 0.1)
				(type default)
			)
			(layer "F.Fab")
		)
		(fp_line
			(start 0.67945 -0.3048)
			(end 0.67945 0.3048)
			(stroke
				(width 0.1)
				(type default)
			)
			(layer "F.Fab")
		)
		(fp_line
			(start -0.67945 -0.305054)
			(end -0.12065 -0.305054)
			(stroke
				(width 0.1)
				(type default)
			)
			(layer "F.Fab")
		)
		(fp_line
			(start -0.12065 -0.305054)
			(end -0.12065 -0.2794)
			(stroke
				(width 0.1)
				(type default)
			)
			(layer "F.Fab")
		)
		(pad "1" smd circle
			(at -0.40005 0 270)
			(size 0 0)
			(layers "F.Cu" "F.Mask" "F.Paste")
			(net "PVCCINFAON_CPU0_VREF")
		)
		(pad "2" smd circle
			(at 0.40005 0 270)
			(size 0 0)
			(layers "F.Cu" "F.Mask" "F.Paste")
			(net "GND")
		)
	)
	(footprint ""
		(layer "F.Cu")
		(at 193.4718 -130.419348 90)
		(property "Reference" "R4607"
			(at 0 0 90)
			(layer "F.SilkS")
			(hide yes)
			(effects
				(font
					(size 1.27 1.27)
				)
			)
		)
		(property "Value" ""
			(at 0 0 90)
			(layer "F.Fab")
			(effects
				(font
					(size 1.27 1.27)
				)
			)
		)
		(duplicate_pad_numbers_are_jumpers no)
		(fp_line
			(start 0.7874 -0.4064)
			(end 0.7874 0.4064)
			(stroke
				(width 0.1524)
				(type default)
			)
			(layer "F.SilkS")
		)
		(fp_line
			(start -0.7874 -0.4064)
			(end 0.7874 -0.4064)
			(stroke
				(width 0.1524)
				(type default)
			)
			(layer "F.SilkS")
		)
		(fp_line
			(start 0.7874 0.4064)
			(end -0.7874 0.4064)
			(stroke
				(width 0.1524)
				(type default)
			)
			(layer "F.SilkS")
		)
		(fp_line
			(start -0.7874 0.4064)
			(end -0.7874 -0.4064)
			(stroke
				(width 0.1524)
				(type default)
			)
			(layer "F.SilkS")
		)
		(fp_line
			(start -0.12065 -0.305054)
			(end -0.12065 -0.2794)
			(stroke
				(width 0.1)
				(type default)
			)
			(layer "F.Fab")
		)
		(fp_line
			(start -0.67945 -0.305054)
			(end -0.12065 -0.305054)
			(stroke
				(width 0.1)
				(type default)
			)
			(layer "F.Fab")
		)
		(fp_line
			(start 0.67945 -0.3048)
			(end 0.67945 0.3048)
			(stroke
				(width 0.1)
				(type default)
			)
			(layer "F.Fab")
		)
		(fp_line
			(start 0.12065 -0.3048)
			(end 0.67945 -0.3048)
			(stroke
				(width 0.1)
				(type default)
			)
			(layer "F.Fab")
		)
		(fp_line
			(start 0.12065 -0.2794)
			(end 0.12065 -0.3048)
			(stroke
				(width 0.1)
				(type default)
			)
			(layer "F.Fab")
		)
		(fp_line
			(start -0.12065 -0.2794)
			(end 0.12065 -0.2794)
			(stroke
				(width 0.1)
				(type default)
			)
			(layer "F.Fab")
		)
		(fp_line
			(start 0.120396 0.2794)
			(end -0.12065 0.2794)
			(stroke
				(width 0.1)
				(type default)
			)
			(layer "F.Fab")
		)
		(fp_line
			(start -0.12065 0.2794)
			(end -0.12065 0.3048)
			(stroke
				(width 0.1)
				(type default)
			)
			(layer "F.Fab")
		)
		(fp_line
			(start 0.67945 0.3048)
			(end 0.120396 0.3048)
			(stroke
				(width 0.1)
				(type default)
			)
			(layer "F.Fab")
		)
		(fp_line
			(start 0.120396 0.3048)
			(end 0.120396 0.2794)
			(stroke
				(width 0.1)
				(type default)
			)
			(layer "F.Fab")
		)
		(fp_line
			(start -0.12065 0.3048)
			(end -0.67945 0.3048)
			(stroke
				(width 0.1)
				(type default)
			)
			(layer "F.Fab")
		)
		(fp_line
			(start -0.67945 0.3048)
			(end -0.67945 -0.305054)
			(stroke
				(width 0.1)
				(type default)
			)
			(layer "F.Fab")
		)
		(pad "1" smd circle
			(at -0.40005 0 90)
			(size 0 0)
			(layers "F.Cu" "F.Mask" "F.Paste")
			(net "LED_HDD_ACTIVITY_B_N")
		)
		(pad "2" smd circle
			(at 0.40005 0 90)
			(size 0 0)
			(layers "F.Cu" "F.Mask" "F.Paste")
			(net "LED_HDD_ACTIVITY_B_PLD_N")
		)
	)
	(footprint ""
		(layer "F.Cu")
		(at 420.682166 -134.130034 180)
		(property "Reference" "PC225"
			(at 0 0 180)
			(layer "F.SilkS")
			(hide yes)
			(effects
				(font
					(size 1.27 1.27)
				)
			)
		)
		(property "Value" ""
			(at 0 0 180)
			(layer "F.Fab")
			(effects
				(font
					(size 1.27 1.27)
				)
			)
		)
		(duplicate_pad_numbers_are_jumpers no)
		(fp_line
			(start 0.7874 0.4064)
			(end -0.7874 0.4064)
			(stroke
				(width 0.1524)
				(type default)
			)
			(layer "F.SilkS")
		)
		(fp_line
			(start 0.7874 -0.4064)
			(end 0.7874 0.4064)
			(stroke
				(width 0.1524)
				(type default)
			)
			(layer "F.SilkS")
		)
		(fp_line
			(start -0.7874 0.4064)
			(end -0.7874 -0.4064)
			(stroke
				(width 0.1524)
				(type default)
			)
			(layer "F.SilkS")
		)
		(fp_line
			(start -0.7874 -0.4064)
			(end 0.7874 -0.4064)
			(stroke
				(width 0.1524)
				(type default)
			)
			(layer "F.SilkS")
		)
		(fp_line
			(start 0.67945 0.3048)
			(end 0.120396 0.3048)
			(stroke
				(width 0.1)
				(type default)
			)
			(layer "F.Fab")
		)
		(fp_line
			(start 0.67945 -0.3048)
			(end 0.67945 0.3048)
			(stroke
				(width 0.1)
				(type default)
			)
			(layer "F.Fab")
		)
		(fp_line
			(start 0.12065 -0.2794)
			(end 0.12065 -0.3048)
			(stroke
				(width 0.1)
				(type default)
			)
			(layer "F.Fab")
		)
		(fp_line
			(start 0.12065 -0.3048)
			(end 0.67945 -0.3048)
			(stroke
				(width 0.1)
				(type default)
			)
			(layer "F.Fab")
		)
		(fp_line
			(start 0.120396 0.3048)
			(end 0.120396 0.2794)
			(stroke
				(width 0.1)
				(type default)
			)
			(layer "F.Fab")
		)
		(fp_line
			(start 0.120396 0.2794)
			(end -0.12065 0.2794)
			(stroke
				(width 0.1)
				(type default)
			)
			(layer "F.Fab")
		)
		(fp_line
			(start -0.12065 0.3048)
			(end -0.67945 0.3048)
			(stroke
				(width 0.1)
				(type default)
			)
			(layer "F.Fab")
		)
		(fp_line
			(start -0.12065 0.2794)
			(end -0.12065 0.3048)
			(stroke
				(width 0.1)
				(type default)
			)
			(layer "F.Fab")
		)
		(fp_line
			(start -0.12065 -0.2794)
			(end 0.12065 -0.2794)
			(stroke
				(width 0.1)
				(type default)
			)
			(layer "F.Fab")
		)
		(fp_line
			(start -0.12065 -0.305054)
			(end -0.12065 -0.2794)
			(stroke
				(width 0.1)
				(type default)
			)
			(layer "F.Fab")
		)
		(fp_line
			(start -0.67945 0.3048)
			(end -0.67945 -0.305054)
			(stroke
				(width 0.1)
				(type default)
			)
			(layer "F.Fab")
		)
		(fp_line
			(start -0.67945 -0.305054)
			(end -0.12065 -0.305054)
			(stroke
				(width 0.1)
				(type default)
			)
			(layer "F.Fab")
		)
		(pad "1" smd circle
			(at -0.40005 0 180)
			(size 0 0)
			(layers "F.Cu" "F.Mask" "F.Paste")
			(net "PVCCINFAON_CPU0_VCC")
		)
		(pad "2" smd circle
			(at 0.40005 0 180)
			(size 0 0)
			(layers "F.Cu" "F.Mask" "F.Paste")
			(net "GND")
		)
	)
	(footprint ""
		(layer "F.Cu")
		(at 340.346284 -337.214718 -90)
		(property "Reference" "PC254_P0_6"
			(at 0 0 270)
			(layer "F.SilkS")
			(hide yes)
			(effects
				(font
					(size 1.27 1.27)
				)
			)
		)
		(property "Value" ""
			(at 0 0 270)
			(layer "F.Fab")
			(effects
				(font
					(size 1.27 1.27)
				)
			)
		)
		(duplicate_pad_numbers_are_jumpers no)
		(fp_line
			(start -0.7874 0.4064)
			(end -0.7874 -0.4064)
			(stroke
				(width 0.1524)
				(type default)
			)
			(layer "F.SilkS")
		)
		(fp_line
			(start 0.7874 0.4064)
			(end -0.7874 0.4064)
			(stroke
				(width 0.1524)
				(type default)
			)
			(layer "F.SilkS")
		)
		(fp_line
			(start -0.7874 -0.4064)
			(end 0.7874 -0.4064)
			(stroke
				(width 0.1524)
				(type default)
			)
			(layer "F.SilkS")
		)
		(fp_line
			(start 0.7874 -0.4064)
			(end 0.7874 0.4064)
			(stroke
				(width 0.1524)
				(type default)
			)
			(layer "F.SilkS")
		)
		(fp_line
			(start -0.67945 0.3048)
			(end -0.67945 -0.305054)
			(stroke
				(width 0.1)
				(type default)
			)
			(layer "F.Fab")
		)
		(fp_line
			(start -0.12065 0.3048)
			(end -0.67945 0.3048)
			(stroke
				(width 0.1)
				(type default)
			)
			(layer "F.Fab")
		)
		(fp_line
			(start 0.120396 0.3048)
			(end 0.120396 0.2794)
			(stroke
				(width 0.1)
				(type default)
			)
			(layer "F.Fab")
		)
		(fp_line
			(start 0.67945 0.3048)
			(end 0.120396 0.3048)
			(stroke
				(width 0.1)
				(type default)
			)
			(layer "F.Fab")
		)
		(fp_line
			(start -0.12065 0.2794)
			(end -0.12065 0.3048)
			(stroke
				(width 0.1)
				(type default)
			)
			(layer "F.Fab")
		)
		(fp_line
			(start 0.120396 0.2794)
			(end -0.12065 0.2794)
			(stroke
				(width 0.1)
				(type default)
			)
			(layer "F.Fab")
		)
		(fp_line
			(start -0.12065 -0.2794)
			(end 0.12065 -0.2794)
			(stroke
				(width 0.1)
				(type default)
			)
			(layer "F.Fab")
		)
		(fp_line
			(start 0.12065 -0.2794)
			(end 0.12065 -0.3048)
			(stroke
				(width 0.1)
				(type default)
			)
			(layer "F.Fab")
		)
		(fp_line
			(start 0.12065 -0.3048)
			(end 0.67945 -0.3048)
			(stroke
				(width 0.1)
				(type default)
			)
			(layer "F.Fab")
		)
		(fp_line
			(start 0.67945 -0.3048)
			(end 0.67945 0.3048)
			(stroke
				(width 0.1)
				(type default)
			)
			(layer "F.Fab")
		)
		(fp_line
			(start -0.67945 -0.305054)
			(end -0.12065 -0.305054)
			(stroke
				(width 0.1)
				(type default)
			)
			(layer "F.Fab")
		)
		(fp_line
			(start -0.12065 -0.305054)
			(end -0.12065 -0.2794)
			(stroke
				(width 0.1)
				(type default)
			)
			(layer "F.Fab")
		)
		(pad "1" smd circle
			(at -0.40005 0 270)
			(size 0 0)
			(layers "F.Cu" "F.Mask" "F.Paste")
			(net "SW_P12V_PVCCIN_CPU0_FLT")
		)
		(pad "2" smd circle
			(at 0.40005 0 270)
			(size 0 0)
			(layers "F.Cu" "F.Mask" "F.Paste")
			(net "GND")
		)
	)
	(footprint ""
		(layer "F.Cu")
		(at 73.94448 -160.212278 180)
		(property "Reference" "PR558"
			(at 0 0 180)
			(layer "F.SilkS")
			(hide yes)
			(effects
				(font
					(size 1.27 1.27)
				)
			)
		)
		(property "Value" ""
			(at 0 0 180)
			(layer "F.Fab")
			(effects
				(font
					(size 1.27 1.27)
				)
			)
		)
		(duplicate_pad_numbers_are_jumpers no)
		(fp_line
			(start 0.7874 0.4064)
			(end -0.7874 0.4064)
			(stroke
				(width 0.1524)
				(type default)
			)
			(layer "F.SilkS")
		)
		(fp_line
			(start 0.7874 -0.4064)
			(end 0.7874 0.4064)
			(stroke
				(width 0.1524)
				(type default)
			)
			(layer "F.SilkS")
		)
		(fp_line
			(start -0.7874 0.4064)
			(end -0.7874 -0.4064)
			(stroke
				(width 0.1524)
				(type default)
			)
			(layer "F.SilkS")
		)
		(fp_line
			(start -0.7874 -0.4064)
			(end 0.7874 -0.4064)
			(stroke
				(width 0.1524)
				(type default)
			)
			(layer "F.SilkS")
		)
		(fp_line
			(start 0.67945 0.3048)
			(end 0.120396 0.3048)
			(stroke
				(width 0.1)
				(type default)
			)
			(layer "F.Fab")
		)
		(fp_line
			(start 0.67945 -0.3048)
			(end 0.67945 0.3048)
			(stroke
				(width 0.1)
				(type default)
			)
			(layer "F.Fab")
		)
		(fp_line
			(start 0.12065 -0.2794)
			(end 0.12065 -0.3048)
			(stroke
				(width 0.1)
				(type default)
			)
			(layer "F.Fab")
		)
		(fp_line
			(start 0.12065 -0.3048)
			(end 0.67945 -0.3048)
			(stroke
				(width 0.1)
				(type default)
			)
			(layer "F.Fab")
		)
		(fp_line
			(start 0.120396 0.3048)
			(end 0.120396 0.2794)
			(stroke
				(width 0.1)
				(type default)
			)
			(layer "F.Fab")
		)
		(fp_line
			(start 0.120396 0.2794)
			(end -0.12065 0.2794)
			(stroke
				(width 0.1)
				(type default)
			)
			(layer "F.Fab")
		)
		(fp_line
			(start -0.12065 0.3048)
			(end -0.67945 0.3048)
			(stroke
				(width 0.1)
				(type default)
			)
			(layer "F.Fab")
		)
		(fp_line
			(start -0.12065 0.2794)
			(end -0.12065 0.3048)
			(stroke
				(width 0.1)
				(type default)
			)
			(layer "F.Fab")
		)
		(fp_line
			(start -0.12065 -0.2794)
			(end 0.12065 -0.2794)
			(stroke
				(width 0.1)
				(type default)
			)
			(layer "F.Fab")
		)
		(fp_line
			(start -0.12065 -0.305054)
			(end -0.12065 -0.2794)
			(stroke
				(width 0.1)
				(type default)
			)
			(layer "F.Fab")
		)
		(fp_line
			(start -0.67945 0.3048)
			(end -0.67945 -0.305054)
			(stroke
				(width 0.1)
				(type default)
			)
			(layer "F.Fab")
		)
		(fp_line
			(start -0.67945 -0.305054)
			(end -0.12065 -0.305054)
			(stroke
				(width 0.1)
				(type default)
			)
			(layer "F.Fab")
		)
		(pad "1" smd circle
			(at -0.40005 0 180)
			(size 0 0)
			(layers "F.Cu" "F.Mask" "F.Paste")
			(net "VSENSE_PVCCD_HV_CPU1_DN")
		)
		(pad "2" smd circle
			(at 0.40005 0 180)
			(size 0 0)
			(layers "F.Cu" "F.Mask" "F.Paste")
			(net "GND")
		)
	)
)
